FILE_TYPE = CONNECTIVITY;
{Allegro Design Entry HDL 17.2-2016 S081 (4005846) 1/11/2022}
"PAGE_NUMBER" = 10;
0"NC";
1"P12V_AUX\g";
2"P12V_AUX\g";
3"GND\g";
4"GND\g";
5"GND\g";
6"GND\g";
7"P2E_GPU_TX_C_DN";
8"P2E_GPU_TX_C_DP";
9"USB3_FPNL_TXN";
10"PCH_BEEP_LED";
11"HDD_LED_N";
12"USB3_FPNL_TXP";
13"QSPI_2_PLD_IO2";
14"USB_FPNL_DN";
15"USB_HOST_BMC_A_DP";
16"TP_GF1_B44";
17"IRQ_SGPIO_N";
18"SGPIO_CLK_1";
19"SGPIO_LD_0";
20"SGPIO_CLK_0";
21"SGPIO_DO_0";
22"SGPIO_DI_0";
23"SGPIO_DO_1";
24"SGPIO_DI_1";
25"P3V_BAT_R";
26"RMII_CSRDV";
27"RMII_OCP_RCLKI";
28"SPI_SYS_HOLD_R_IO3";
29"SPI_SYS_WP_R_IO2";
30"SMB_BMC_MM4_SCL";
31"SMB_BMC_MM3_SDA";
32"SMB_BMC_MM3_SCL";
33"TP_GF_B62";
34"TP_GF_B63";
35"HDD_LED_R_N";
36"FM_PCH_BEEP_LED";
37"FM_PRSNT_0_R_N";
38"UART_BIC_GF_TXD";
39"UART_BIC_GF_RXD";
40"UART_SYS_DBG_TX";
41"UART_SYS_DBG_RX";
42"RST_SRST_PLD_BMC_R_N";
43"FM_SOL_UART_CH_SEL";
44"IRQ_BMC_LPC_SERIRQ_ESPI_GF";
45"ESPI_LPC_LAD1_IO1";
46"ESPI_LPC_LAD2_IO2";
47"LPC_ESPI_SEL";
48"SPI_SYS_R_MOSI";
49"SPI_SYS_R_MISO";
50"RMII_TXEN";
51"RMII_TXD0";
52"RMII_RXER";
53"RMII_RXD0";
54"PECI_BMC";
55"SGPIO_LD_1";
56"RST_SGPIO_RESET_N";
57"PVCCIO_PECI_BMC";
58"RMII_TXD1";
59"SPI_SYS_CS0_N";
60"SPI_SYS_R_CLK";
61"ESPI_LPC_LAD0_IO0";
62"ESPI_HOST_LPC_BMC_CLK";
63"SPI_TPM_CS_N";
64"FM_PRSNT_1_N";
65"I3C3_SPD_SDA";
66"I3C1_SPD_SCL";
67"I3C1_SPD_SDA";
68"I3C2_SPD_SDA";
69"I3C3_SPD_SCL";
70"I3C4_SPD_SCL";
71"SMB_BMC_MM14_R1_SCL";
72"SMB_BMC_MM14_R1_SDA";
73"SMB_BMC_MM14_SDA";
74"SMB_BMC_MM14_SCL";
75"I3C4_SPD_SDA";
76"I3C2_SPD_SCL";
77"TP_GF_A62";
78"TP_GF_A63";
79"PWRGD_PSU_AC_PWROK";
80"QSPI_2_PLD_CLK";
81"FM_VIRTUAL_RESEAT";
82"RMII_RXD1";
83"AC_PWR_BTN_N";
84"QSPI_2_PLD_IO0";
85"QSPI_2_PLD_IO1";
86"QSPI_2_PLD_IO3";
87"USB_HOST_BMC_B_DP";
88"USB_HOST_BMC_B_DN";
89"USB_HOST_BMC_A_DN";
90"USB_FPNL_DP";
91"FM_HDD_LED_N";
92"PCH_BEEP_R_LED";
93"SMB_BMC_MM2_SCL";
94"SMB_BMC_MM2_SCL_R1";
95"SMB_BMC_MM1_SDA";
96"SMB_BMC_MM1_SCL";
97"SMB_BMC_MM5_SCL";
98"SMB_BMC_MM2_SDA";
99"SMB_BMC_MM4_SDA";
100"SMB_BMC_MM5_SDA";
101"CLK_100M_PCH_DP";
102"CLK_100M_PCH_DN";
103"P2E_PCH_TX_C_DN";
104"P2E_PCH_TX_C_DP";
105"P2E_PCH_RX_DP";
106"P2E_PCH_RX_DN";
107"SMB_BMC_MM6_SCL";
108"SMB_BMC_MM6_SDA";
109"SMB_BMC_MM7_SCL";
110"SMB_BMC_MM7_SDA";
111"SMB_BMC_MM8_SCL";
112"SMB_BMC_MM9_SCL";
113"SMB_BMC_MM8_SDA";
114"JTAG_MB_TCK";
115"JTAG_MB_TMS";
116"PWRGD_PSU_AC_PWROK_R";
117"IRQ_SMI_ACTIVE_GF_N";
118"FM_INTRUDER_N";
119"RST_ROT_CPU_N";
120"FM_BMC_UARTSW_MSB_N";
121"RST_PLTRST_N";
122"FM_DBP_BMC_PRDY_N";
123"FM_DBP_CPU_PREQ_GF_R_N";
124"PWRGD_SYS_PWROK";
125"SYS_PWRBTN_N";
126"RST_MB_STBY_N";
127"TP_GF_A45";
128"JTAG_MB_TDI";
129"JTAG_MB_TDO";
130"SMB_BMC_MM12_SCL";
131"SMB_BMC_MM12_SDA";
132"SMB_BMC_MM13_SCL";
133"SMB_BMC_MM13_SDA";
134"FM_JTAG_SEL";
135"FM_BMC_UARTSW_LSB_N";
136"FM_PRSNT_1_N";
137"USB3_FPNL_RXP";
138"USB3_FPNL_RXN";
139"CLK_100M_GPU_DN";
140"CLK_100M_GPU_DP";
141"P2E_GPU_RX_DN";
142"P2E_GPU_RX_DP";
143"SMB_BMC_MM10_SDA";
144"SMB_BMC_MM9_SDA";
145"SMB_BMC_MM10_SCL";
146"ESPI_LPC_LAD3_IO3";
147"RST_BMC_LPC_ESPI_N";
148"ESPI_HOST_LPC_BMC_LFRAME_N";
149"H_CPU_CATERR_LVC2_R2_N";
%"UNIVERSAL_POWER"
"1","(-7300,3200)","0","logical_power","I173";
;
HDL_POWER"P12V_AUX"
CDS_LIB"logical_power";
"A"2;
%"UNIVERSAL_GND"
"1","(-9300,-1700)","0","logical_power","I174";
;
HDL_POWER"GND"
CDS_LIB"logical_power";
"A"3;
%"UNIVERSAL_GND"
"1","(-7300,-1700)","0","logical_power","I175";
;
HDL_POWER"GND"
CDS_LIB"logical_power";
"A"5;
%"Q_RES"
"1","(-10325,-50)","0","pure_quanta","I293";
;
MATERIAL"CHIP"
VALUE"33.2"
SEC_TYPE"0402LF"
PACK_TYPE"0402LF"
TOLERANCE"1%"
PART_NUMBER"CS03322FB03"
WATTAGE"1/16W"
CDS_LIB"pure_quanta"
LOCATION"R243"
SEC"1";
"B"
$PN"2"116;
"A"
$PN"1"79;
%"UNIVERSAL_POWER"
"1","(-10225,3725)","0","logical_power","I446";
;
HDL_POWER"P12V_AUX"
CDS_LIB"logical_power";
"A"1;
%"UNIVERSAL_GND"
"1","(-10225,3000)","0","logical_power","I447";
;
HDL_POWER"GND"
CDS_LIB"logical_power";
"A"4;
%"Q_RES"
"1","(-6425,2850)","2","pure_quanta","I456";
;
MATERIAL"CHIP"
VALUE"0"
CDS_LIB"pure_quanta"
PART_NUMBER"CS00002JB13"
TOLERANCE"5%"
WATTAGE"1/16W"
PACK_TYPE"0402LF"
LOCATION"R822"
$SEC"1"
CDS_SEC"1";
"B"
$PN"2"37;
"A"
$PN"1"64;
%"Q_RES"
"1","(-10350,2200)","0","pure_quanta","I458";
;
MATERIAL"CHIP"
VALUE"33.2"
SEC_TYPE"0402LF"
CDS_LIB"pure_quanta"
WATTAGE"1/16W"
PACK_TYPE"0402LF"
PART_NUMBER"CS03322FB03"
TOLERANCE"1%"
LOCATION"R36"
SEC"1";
"B"
$PN"2"71;
"A"
$PN"1"74;
%"Q_RES"
"1","(-10350,2150)","0","pure_quanta","I459";
;
VALUE"33.2"
MATERIAL"CHIP"
SEC_TYPE"0402LF"
CDS_LIB"pure_quanta"
WATTAGE"1/16W"
PACK_TYPE"0402LF"
PART_NUMBER"CS03322FB03"
TOLERANCE"1%"
LOCATION"R46"
SEC"1";
"B"
$PN"2"72;
"A"
$PN"1"73;
%"Q_CAP"
"1","(-4675,-50)","0","pure_quanta","I503";
;
TOLERANCE"10%"
MATERIAL"EMPTY"
VALUE"0.1UF"
VOLTAGE"25V"
PACK_TYPE"0402"
PART_NUMBER"CH4104K1B00"
CDS_LIB"pure_quanta"
SEC_TYPE"0402"
LOCATION"C174"
SEC"1";
"B"
$PN"2"6;
"A"
$PN"1"25;
%"UNIVERSAL_GND"
"1","(-4675,-300)","0","logical_power","I504";
;
CDS_LIB"logical_power"
HDL_POWER"GND";
"A"6;
%"FCONN168_ME1016810202011_SCM"
"1","(-8275,800)","0","pure_quanta","I553";
;
PART_NUMBER"GOLD244"
PART_TYPE"SMLF"
MATERIAL"EMPTY"
VALUE"FCONN168_ME1016810202011_SCM"
CDS_LIB"pure_quanta"
CDS_LMAN_SYM_OUTLINE"-625,2250,625,-2250"
NEEDS_NO_SIZE"TRUE"
$LOCATION"GF1"
CDS_LOCATION"GF1"
$SEC"1"
CDS_SEC"1";
"GND_B70"
$PN"B70"5;
"PCIE_HPM_TXN_3"
$PN"B69"92;
"PCIE_HPM_TXP_3"
$PN"B68"35;
"GND_B67"
$PN"B67"5;
"PCIE_HPM_TXN_2"
$PN"B66"7;
"PCIE_HPM_TXP_2"
$PN"B65"8;
"GND_B64"
$PN"B64"5;
"PCIE_HPM_TXN_1"
$PN"B63"34;
"PCIE_HPM_TXP_1"
$PN"B62"33;
"GND_B61"
$PN"B61"5;
"PCIE_HPM_TXN_0"
$PN"B60"9;
"PCIE_HPM_TXP_0"
$PN"B59"12;
"GND_B58"
$PN"B58"5;
"RSVD1"
$PN"B57"14;
"RSVD0"
$PN"B56"90;
"GND_B55"
$PN"B55"5;
"USB1_DN"
$PN"B54"89;
"USB1_DP"
$PN"B53"15;
"GND_B52"
$PN"B52"5;
"USB2_DN"
$PN"B51"88;
"USB2_DP"
$PN"B50"87;
"GND_B49"
$PN"B49"5;
"QSPI1_D3"
$PN"B48"86;
"QSPI1_D2"
$PN"B47"13;
"QSPI1_D1"
$PN"B46"85;
"QSPI1_D0"
$PN"B45"84;
"QSPI1_CS0_N \B"
$PN"B44"16;
"QSPI1_CLK"
$PN"B43"80;
"QSPI0_CS1_N \B"
$PN"B42"83;
"P3V0_BAT"
$PN"B41"25;
"SGPIO_INTR_N \B"
$PN"B40"17;
"SGPIO_RESET_N \B"
$PN"B39"56;
"GND_B38"
$PN"B38"5;
"SGPIO1_LD"
$PN"B37"55;
"SGPIO1_DI"
$PN"B36"24;
"RSVD2"
$PN"B35"18;
"SGPIO1_DO"
$PN"B34"23;
"GND_B33"
$PN"B33"5;
"SGPIO0_LD"
$PN"B32"19;
"SGPIO0_DI"
$PN"B31"22;
"SGPIO_CLK"
$PN"B30"20;
"SGPIO0_DO"
$PN"B29"21;
"PVCCIO_PECI"
$PN"B28"57;
"PECI_BMC"
$PN"B27"54;
"GND_B26"
$PN"B26"5;
"NCSI_RXD1"
$PN"B25"82;
"NCSI_RXD0"
$PN"B24"53;
"NCSI_RXER"
$PN"B23"52;
"NCSI_TXD1"
$PN"B22"58;
"NCSI_TXD0"
$PN"B21"51;
"NCSI_TXEN"
$PN"B20"50;
"NCSI_CRS_DV"
$PN"B19"26;
"NCSI_CLK"
$PN"B18"27;
"GND_B17"
$PN"B17"5;
"QSPI0_D3"
$PN"B16"28;
"QSPI0_D2"
$PN"B15"29;
"QSPI0_D1"
$PN"B14"49;
"QSPI0_D0"
$PN"B13"48;
"QSPI0_CS0_N \B"
$PN"B12"59;
"QSPI0_CLK"
$PN"B11"60;
"GND_B10"
$PN"B10"5;
"RSVD3 \B"
$PN"B9"47;
"ESPI_IO3"
$PN"B8"146;
"ESPI_IO2"
$PN"B7"46;
"ESPI_IO1"
$PN"B6"45;
"ESPI_IO0"
$PN"B5"61;
"ESPI_RESET_N \B"
$PN"B4"147;
"ESPI_ALERT_N \B"
$PN"B3"44;
"ESPI_CS0_N \B"
$PN"B2"148;
"ESPI_CLK"
$PN"B1"62;
"SPI0_MISO"
$PN"OB14"43;
"SPI0_MOSI"
$PN"OB13"149;
"SPI0_CS_N \B"
$PN"OB12"63;
"SPI0_CLK"
$PN"OB11"42;
"GND_OB10"
$PN"OB10"5;
"UART0_SCM_RX"
$PN"OB9"41;
"UART0_SCM_TX"
$PN"OB8"40;
"GND_OB7"
$PN"OB7"5;
"UART1_SCM_RX"
$PN"OB6"39;
"UART1_SCM_TX"
$PN"OB5"38;
"GND_OB4"
$PN"OB4"5;
"PRSNT0_N \B"
$PN"OB3"37;
"P12V_AUX_OB2"
$PN"OB2"2;
"P12V_AUX_OB1"
$PN"OB1"2;
"GND_A70"
$PN"A70"3;
"PCIE_HPM_RXN_3"
$PN"A69"139;
"PCIE_HPM_RXP_3"
$PN"A68"140;
"GND_A67"
$PN"A67"3;
"PCIE_HPM_RXN_2"
$PN"A66"141;
"PCIE_HPM_RXP_2"
$PN"A65"142;
"GND_A64"
$PN"A64"3;
"PCIE_HPM_RXN_1"
$PN"A63"78;
"PCIE_HPM_RXP_1"
$PN"A62"77;
"GND_A61"
$PN"A61"3;
"PCIE_HPM_RXN_0"
$PN"A60"138;
"PCIE_HPM_RXP_0"
$PN"A59"137;
"GND_A58"
$PN"A58"3;
"PRSNT1_N \B"
$PN"A57"136;
"IRQ_N \B"
$PN"A56"117;
"SPARE0"
$PN"A55"135;
"CHASI_N \B"
$PN"A54"118;
"ROT_CPU_RST_N \B"
$PN"A53"119;
"SPARE1"
$PN"A52"120;
"RST_PLTRST_BUF_N \B"
$PN"A51"121;
"DBP_PRDY_N \B"
$PN"A50"122;
"DBP_PREQ_N \B"
$PN"A49"123;
"SYS_PWROK"
$PN"A48"124;
"SYS_PWRBTN_N \B"
$PN"A47"125;
"HPM_STBY_RST_N \B"
$PN"A46"126;
"HPM_STBY_EN"
$PN"A45"127;
"HPM_STBY_RDY"
$PN"A44"116;
"HPM_FW_RECOVERY"
$PN"A43"134;
"GND_A42"
$PN"A42"3;
"I2C_12_SDA"
$PN"A41"133;
"I2C_12_SCL"
$PN"A40"132;
"I2C_11_SDA"
$PN"A39"131;
"I2C_11_SCL"
$PN"A38"130;
"JTAG_TDO"
$PN"A37"129;
"JTAG_TDI"
$PN"A36"128;
"JTAG_TMS"
$PN"A35"115;
"JTAG_TCK"
$PN"A34"114;
"GND_A33"
$PN"A33"3;
"I2C_10_SDA"
$PN"A32"143;
"I2C_10_SCL"
$PN"A31"145;
"I2C_9_SDA"
$PN"A30"144;
"I2C_9_SCL"
$PN"A29"112;
"I2C_8_SDA"
$PN"A28"113;
"I2C_8_SCL"
$PN"A27"111;
"I2C_7_SDA"
$PN"A26"110;
"I2C_7_SCL"
$PN"A25"109;
"I2C_6_SDA"
$PN"A24"108;
"I2C_6_SCL"
$PN"A23"107;
"GND_A22"
$PN"A22"3;
"PCIE_BMC_RX_DN"
$PN"A21"103;
"PCIE_BMC_RX_DP"
$PN"A20"104;
"GND_A19"
$PN"A19"3;
"PCIE_BMC_TX_DN"
$PN"A18"106;
"PCIE_BMC_TX_DP"
$PN"A17"105;
"GND_A16"
$PN"A16"3;
"CLK_100M_PCIE_DN"
$PN"A15"102;
"CLK_100M_PCIE_DP"
$PN"A14"101;
"GND_A13"
$PN"A13"3;
"I2C_5_SDA"
$PN"A12"100;
"I2C_5_SCL"
$PN"A11"97;
"I2C_4_SDA"
$PN"A10"99;
"I2C_4_SCL"
$PN"A9"30;
"I2C_3_SDA"
$PN"A8"31;
"I2C_3_SCL"
$PN"A7"32;
"I2C_2_SDA"
$PN"A6"98;
"I2C_2_SCL"
$PN"A5"94;
"I2C_1_SDA"
$PN"A4"95;
"I2C_1_SCL"
$PN"A3"96;
"I2C_0_SDA"
$PN"A2"72;
"I2C_0_SCL"
$PN"A1"71;
"VIRTUAL_RESEAT"
$PN"OA14"81;
"GND_OA13"
$PN"OA13"3;
"I3C_3_SDA"
$PN"OA12"75;
"I3C_3_SCL"
$PN"OA11"70;
"I3C_2_SDA"
$PN"OA10"65;
"I3C_2_SCL"
$PN"OA9"69;
"I3C_1_SDA"
$PN"OA8"68;
"I3C_1_SCL"
$PN"OA7"76;
"I3C_0_SDA"
$PN"OA6"67;
"I3C_0_SCL"
$PN"OA5"66;
"GND_OA4"
$PN"OA4"3;
"GND_OA3"
$PN"OA3"3;
"P12V_AUX_OA2"
$PN"OA2"1;
"P12V_AUX_OA1"
$PN"OA1"1;
%"Q_RES"
"1","(-10350,2000)","0","pure_quanta","I557";
;
VALUE"33.2"
MATERIAL"CHIP"
PACK_TYPE"0402LF"
WATTAGE"1/16W"
PART_NUMBER"CS03322FB03"
TOLERANCE"1%"
CDS_LIB"pure_quanta"
$LOCATION"R455"
CDS_LOCATION"R455"
$SEC"1"
CDS_SEC"1";
"B"
$PN"2"94;
"A"
$PN"1"93;
%"Q_RES"
"1","(-6450,-1250)","2","pure_quanta","I562";
;
VALUE"0"
MATERIAL"EMPTY"
PACK_TYPE"0402LF"
TOLERANCE"5%"
WATTAGE"1/16W"
CDS_LIB"pure_quanta"
PART_NUMBER"CS00002JB13"
$LOCATION"R564"
CDS_LOCATION"R564"
$SEC"1"
CDS_SEC"1";
"B"
$PN"2"35;
"A"
$PN"1"11;
%"Q_RES"
"1","(-6450,-1300)","2","pure_quanta","I565";
;
VALUE"0"
MATERIAL"EMPTY"
CDS_LIB"pure_quanta"
PART_NUMBER"CS00002JB13"
WATTAGE"1/16W"
TOLERANCE"5%"
PACK_TYPE"0402LF"
$LOCATION"R811"
CDS_LOCATION"R811"
$SEC"1"
CDS_SEC"1";
"B"
$PN"2"92;
"A"
$PN"1"10;
%"Q_RES"
"1","(-6175,-1475)","2","pure_quanta","I568";
;
MATERIAL"CHIP"
VALUE"0"
TOLERANCE"5%"
PACK_TYPE"0402LF"
CDS_LIB"pure_quanta"
PART_NUMBER"CS00002JB13"
WATTAGE"1/16W"
$LOCATION"R838"
CDS_LOCATION"R838"
$SEC"1"
CDS_SEC"1";
"B"
$PN"2"91;
"A"
$PN"1"11;
%"Q_RES"
"1","(-6175,-1525)","2","pure_quanta","I569";
;
VALUE"0"
MATERIAL"CHIP"
CDS_LIB"pure_quanta"
PART_NUMBER"CS00002JB13"
WATTAGE"1/16W"
TOLERANCE"5%"
PACK_TYPE"0402LF"
$LOCATION"R847"
CDS_LOCATION"R847"
$SEC"1"
CDS_SEC"1";
"B"
$PN"2"36;
"A"
$PN"1"10;
%"Q_CAP"
"1","(-10225,3375)","0","pure_quanta","I573";
;
TOLERANCE"20%"
MATERIAL"X6S"
PART_NUMBER"CH6223MEA01"
PACK_TYPE"C0805"
VALUE"22UF"
VOLTAGE"16V"
CDS_LIB"pure_quanta"
LOCATION"C329"
$SEC"1"
CDS_SEC"1";
"B"
$PN"2"4;
"A"
$PN"1"1;
%"Q_CAP"
"1","(-9800,3375)","0","pure_quanta","I574";
;
PART_NUMBER"CH6223MEA01"
VOLTAGE"16V"
PACK_TYPE"C0805"
TOLERANCE"20%"
MATERIAL"X6S"
VALUE"22UF"
CDS_LIB"pure_quanta"
LOCATION"C330"
$SEC"1"
CDS_SEC"1";
"B"
$PN"2"4;
"A"
$PN"1"1;
END.
